# S9S_MB_2U (Grand Teton) — schematic parts with pin connectivity, parts 1607–1607 of 6093; source: Cadence DE-HDL packaged netlist (pstxprt.dat, pstxnet.dat, pstchip.dat)

J14  SCONN288_ADR50017P087CC  SCONN288_ADR50017-P087CC IO  pkg DDR288S_1-1VXB  page 95
  1  VIN_BULK0  POWER  = P12V_S3_AUX_CPU0_NVDIMM
  2  RFU0  TRI  = TP_CHG_CPU0_DIMM2_FRU_0
  3  VIN_MGMT  POWER  = P3V3_AUX
  4  HSCL  IN  = I3C_SPD_DDREFGH_CPU0_LVC1_SCL_5
  5  HSDA  BI  = I3C_SPD_DDREFGH_CPU0_LVC1_SDA
  6  VSS0  POWER  = GND
  7  DQ0_A  BI  = M_G_CPU0_SA_DQ<0>
  8  VSS1  POWER  = GND
  9  DQ1_A  BI  = M_G_CPU0_SA_DQ<1>
  10  VSS2  POWER  = GND
  11  DQS0_A_T  BI  = M_G_CPU0_SA_DQS_DP<0>
  12  DQS0_A_C  BI  = M_G_CPU0_SA_DQS_DN<0>
  13  VSS3  POWER  = GND
  14  DQ4_A  BI  = M_G_CPU0_SA_DQ<4>
  15  VSS4  POWER  = GND
  16  DQ5_A  BI  = M_G_CPU0_SA_DQ<5>
  17  VSS5  POWER  = GND
  18  DQ8_A  BI  = M_G_CPU0_SA_DQ<8>
  19  VSS6  POWER  = GND
  20  DQ9_A  BI  = M_G_CPU0_SA_DQ<9>
  21  VSS7  POWER  = GND
  22  DQS1_A_T  BI  = M_G_CPU0_SA_DQS_DP<1>
  23  DQS1_A_C  BI  = M_G_CPU0_SA_DQS_DN<1>
  24  VSS8  POWER  = GND
  25  DQ12_A  BI  = M_G_CPU0_SA_DQ<12>
  26  VSS9  POWER  = GND
  27  DQ13_A  BI  = M_G_CPU0_SA_DQ<13>
  28  VSS10  POWER  = GND
  29  DQ16_A  BI  = M_G_CPU0_SA_DQ<16>
  30  VSS11  POWER  = GND
  31  DQ17_A  BI  = M_G_CPU0_SA_DQ<17>
  32  VSS12  POWER  = GND
  33  DQS2_A_T  BI  = M_G_CPU0_SA_DQS_DP<2>
  34  DQS2_A_C  BI  = M_G_CPU0_SA_DQS_DN<2>
  35  VSS13  POWER  = GND
  36  DQ20_A  BI  = M_G_CPU0_SA_DQ<20>
  37  VSS14  POWER  = GND
  38  DQ21_A  BI  = M_G_CPU0_SA_DQ<21>
  39  VSS15  POWER  = GND
  40  DQ24_A  BI  = M_G_CPU0_SA_DQ<24>
  41  VSS16  POWER  = GND
  42  DQ25_A  BI  = M_G_CPU0_SA_DQ<25>
  43  VSS17  POWER  = GND
  44  DQS3_A_T  BI  = M_G_CPU0_SA_DQS_DP<3>
  45  DQS3_A_C  BI  = M_G_CPU0_SA_DQS_DN<3>
  46  VSS18  POWER  = GND
  47  DQ28_A  BI  = M_G_CPU0_SA_DQ<28>
  48  VSS19  POWER  = GND
  49  DQ29_A  BI  = M_G_CPU0_SA_DQ<29>
  50  VSS20  POWER  = GND
  51  CB0_A  BI  = M_G_CPU0_SA_CB<0>
  52  VSS21  POWER  = GND
  53  CB1_A  BI  = M_G_CPU0_SA_CB<1>
  54  VSS22  POWER  = GND
  55  DQS4_A_T  BI  = M_G_CPU0_SA_DQS_DP<4>
  56  DQS4_A_C  BI  = M_G_CPU0_SA_DQS_DN<4>
  57  VSS23  POWER  = GND
  58  CB4_A  BI  = M_G_CPU0_SA_CB<4>
  59  VSS24  POWER  = GND
  60  CB5_A  BI  = M_G_CPU0_SA_CB<5>
  61  VSS25  POWER  = GND
  62  ALERT_N  OUT  = M_G_CPU0_ALERT_N
  63  VSS26  POWER  = GND
  64  CS0_A_N  IN  = M_G_CPU0_SA_CS_N<2>
  65  VSS27  POWER  = GND
  66  CA0_A  IN  = M_G_CPU0_SA_CA<0>
  67  VSS28  POWER  = GND
  68  CA2_A  IN  = M_G_CPU0_SA_CA<2>
  69  VSS29  POWER  = GND
  70  CA4_A  IN  = M_G_CPU0_SA_CA<4>
  71  VSS30  POWER  = GND
  72  CA6_A  IN  = M_G_CPU0_SA_CA<6>
  73  VSS31  POWER  = GND
  74  PAR_A  IN  = M_G_CPU0_SA_PAR
  75  VSS32  POWER  = GND
  76  CA0_B  IN  = M_G_CPU0_SB_CA<0>
  77  VSS33  POWER  = GND
  78  CA2_B  IN  = M_G_CPU0_SB_CA<2>
  79  VSS34  POWER  = GND
  80  CA4_B  IN  = M_G_CPU0_SB_CA<4>
  81  VSS35  POWER  = GND
  82  CA6_B  IN  = M_G_CPU0_SB_CA<6>
  83  VSS36  POWER  = GND
  84  CS0_B_N  IN  = M_G_CPU0_SB_CS_N<2>
  85  VSS37  POWER  = GND
  86  \lbd||rsp_a_n\  OUT  = M_G_CPU0_SA_RSP<1>
  87  \lbs||rsp_b_n\  OUT  = M_G_CPU0_SB_RSP<1>
  88  VSS38  POWER  = GND
  89  CB4_B  BI  = M_G_CPU0_SB_CB<4>
  90  VSS39  POWER  = GND
  91  CB5_B  BI  = M_G_CPU0_SB_CB<5>
  92  VSS40  POWER  = GND
  93  \dqs9_b_t||tdqs9_b_t||dbi4_b_n\  BI  = M_G_CPU0_SB_DQS_DP<9>
  94  \dqs9_b_c||tdqs9_b_c\  BI  = M_G_CPU0_SB_DQS_DN<9>
  95  VSS41  POWER  = GND
  96  CB0_B  BI  = M_G_CPU0_SB_CB<0>
  97  VSS42  POWER  = GND
  98  CB1_B  BI  = M_G_CPU0_SB_CB<1>
  99  VSS43  POWER  = GND
  100  DQ0_B  BI  = M_G_CPU0_SB_DQ<0>
  101  VSS44  POWER  = GND
  102  DQ1_B  BI  = M_G_CPU0_SB_DQ<1>
  103  VSS45  POWER  = GND
  104  DQS0_B_T  BI  = M_G_CPU0_SB_DQS_DP<0>
  105  DQS0_B_C  BI  = M_G_CPU0_SB_DQS_DN<0>
  106  VSS46  POWER  = GND
  107  DQ4_B  BI  = M_G_CPU0_SB_DQ<4>
  108  VSS47  POWER  = GND
  109  DQ5_B  BI  = M_G_CPU0_SB_DQ<5>
  110  VSS48  POWER  = GND
  111  DQ8_B  BI  = M_G_CPU0_SB_DQ<8>
  112  VSS49  POWER  = GND
  113  DQ9_B  BI  = M_G_CPU0_SB_DQ<9>
  114  VSS50  POWER  = GND
  115  DQS1_B_T  BI  = M_G_CPU0_SB_DQS_DP<1>
  116  DQS1_B_C  BI  = M_G_CPU0_SB_DQS_DN<1>
  117  VSS51  POWER  = GND
  118  DQ12_B  BI  = M_G_CPU0_SB_DQ<12>
  119  VSS52  POWER  = GND
  120  DQ13_B  BI  = M_G_CPU0_SB_DQ<13>
  121  VSS53  POWER  = GND
  122  DQ16_B  BI  = M_G_CPU0_SB_DQ<16>
  123  VSS54  POWER  = GND
  124  DQ17_B  BI  = M_G_CPU0_SB_DQ<17>
  125  VSS55  POWER  = GND
  126  DQS2_B_T  BI  = M_G_CPU0_SB_DQS_DP<2>
  127  DQS2_B_C  BI  = M_G_CPU0_SB_DQS_DN<2>
  128  VSS56  POWER  = GND
  129  DQ20_B  BI  = M_G_CPU0_SB_DQ<20>
  130  VSS57  POWER  = GND
  131  DQ21_B  BI  = M_G_CPU0_SB_DQ<21>
  132  VSS58  POWER  = GND
  133  DQ24_B  BI  = M_G_CPU0_SB_DQ<24>
  134  VSS59  POWER  = GND
  135  DQ25_B  BI  = M_G_CPU0_SB_DQ<25>
  136  VSS60  POWER  = GND
  137  DQS3_B_T  BI  = M_G_CPU0_SB_DQS_DP<3>
  138  DQS3_B_C  BI  = M_G_CPU0_SB_DQS_DN<3>
  139  VSS61  POWER  = GND
  140  DQ28_B  BI  = M_G_CPU0_SB_DQ<28>
  141  VSS62  POWER  = GND
  142  DQ29_B  BI  = M_G_CPU0_SB_DQ<29>
  143  VSS63  POWER  = GND
  144  RFU1  TRI  = TP_CHG_CPU0_DIMM2_FRU_1
  145  VIN_BULK1  POWER  = P12V_S3_AUX_CPU0_NVDIMM
  146  VIN_BULK2  POWER  = P12V_S3_AUX_CPU0_NVDIMM
  147  \pwr_good||fail_n\  BI  = PWRGD_CHG_CPU0_DIMM2
  148  HSA  IN  = PD_CHG_CPU0_DIMM2_SAA
  149  RFU2  TRI  = TP_CHG_CPU0_DIMM2_FRU_2
  150  RFU3  TRI  = TP_CHG_CPU0_DIMM2_FRU_3
  151  VSS64  POWER  = GND
  152  DQ2_A  BI  = M_G_CPU0_SA_DQ<2>
  153  VSS65  POWER  = GND
  154  DQ3_A  BI  = M_G_CPU0_SA_DQ<3>
  155  VSS66  POWER  = GND
  156  \dqs5_a_c||tdqs5_a_c||dqs5_a_t||tdqs5_a_t\  BI  = M_G_CPU0_SA_DQS_DN<5>
  157  \dqs5_a_t||tdqs5_a_t\  BI  = M_G_CPU0_SA_DQS_DP<5>
  158  VSS67  POWER  = GND
  159  DQ6_A  BI  = M_G_CPU0_SA_DQ<6>
  160  VSS68  POWER  = GND
  161  DQ7_A  BI  = M_G_CPU0_SA_DQ<7>
  162  VSS69  POWER  = GND
  163  DQ10_A  BI  = M_G_CPU0_SA_DQ<10>
  164  VSS70  POWER  = GND
  165  DQ11_A  BI  = M_G_CPU0_SA_DQ<11>
  166  VSS71  POWER  = GND
  167  \dqs6_a_c||tdqs6_a_c||dqs6_a_t||tdqs6_a_t\  BI  = M_G_CPU0_SA_DQS_DN<6>
  168  \dqs6_a_t||tdqs6_a_t\  BI  = M_G_CPU0_SA_DQS_DP<6>
  169  VSS72  POWER  = GND
  170  DQ14_A  BI  = M_G_CPU0_SA_DQ<14>
  171  VSS73  POWER  = GND
  172  DQ15_A  BI  = M_G_CPU0_SA_DQ<15>
  173  VSS74  POWER  = GND
  174  DQ18_A  BI  = M_G_CPU0_SA_DQ<18>
  175  VSS75  POWER  = GND
  176  DQ19_A  BI  = M_G_CPU0_SA_DQ<19>
  177  VSS76  POWER  = GND
  178  \dqs7_a_c||tdqs7_a_c\  BI  = M_G_CPU0_SA_DQS_DN<7>
  179  \dqs7_a_t||tdqs7_a_t\  BI  = M_G_CPU0_SA_DQS_DP<7>
  180  VSS77  POWER  = GND
  181  DQ22_A  BI  = M_G_CPU0_SA_DQ<22>
  182  VSS78  POWER  = GND
  183  DQ23_A  BI  = M_G_CPU0_SA_DQ<23>
  184  VSS79  POWER  = GND
  185  DQ26_A  BI  = M_G_CPU0_SA_DQ<26>
  186  VSS80  POWER  = GND
  187  DQ27_A  BI  = M_G_CPU0_SA_DQ<27>
  188  VSS81  POWER  = GND
  189  \dqs8_a_c||tdqs8_a_c\  BI  = M_G_CPU0_SA_DQS_DN<8>
  190  \dqs8_a_t||tdqs8_a_t\  BI  = M_G_CPU0_SA_DQS_DP<8>
  191  VSS82  POWER  = GND
  192  DQ30_A  BI  = M_G_CPU0_SA_DQ<30>
  193  VSS83  POWER  = GND
  194  DQ31_A  BI  = M_G_CPU0_SA_DQ<31>
  195  VSS84  POWER  = GND
  196  CB2_A  BI  = M_G_CPU0_SA_CB<2>
  197  VSS85  POWER  = GND
  198  CB3_A  BI  = M_G_CPU0_SA_CB<3>
  199  VSS86  POWER  = GND
  200  \dqs9_a_c||tdqs9_a_c\  BI  = M_G_CPU0_SA_DQS_DN<9>
  201  \dqs9_a_t||tdqs9_a_t\  BI  = M_G_CPU0_SA_DQS_DP<9>
  202  VSS87  POWER  = GND
  203  CB6_A  BI  = M_G_CPU0_SA_CB<6>
  204  VSS88  POWER  = GND
  205  CB7_A  BI  = M_G_CPU0_SA_CB<7>
  206  VSS89  POWER  = GND
  207  RESET_N  IN  = RST_M_GH_CPU0_FPGA_N
  208  VSS90  POWER  = GND
  209  CS1_A_N  IN  = M_G_CPU0_SA_CS_N<3>
  210  VSS91  POWER  = GND
  211  CA1_A  IN  = M_G_CPU0_SA_CA<1>
  212  VSS92  POWER  = GND
  213  CA3_A  IN  = M_G_CPU0_SA_CA<3>
  214  VSS93  POWER  = GND
  215  CA5_A  IN  = M_G_CPU0_SA_CA<5>
  216  VSS94  POWER  = GND
  217  CK_T  IN  = M_G_CPU0_CLK_DP<1>
  218  CK_C  IN  = M_G_CPU0_CLK_DN<1>
  219  VSS95  POWER  = GND
  220  RFU4  TRI  = TP_CHG_CPU0_DIMM2_FRU_4
  221  CA1_B  IN  = M_G_CPU0_SB_CA<1>
  222  VSS96  POWER  = GND
  223  CA3_B  IN  = M_G_CPU0_SB_CA<3>
  224  VSS97  POWER  = GND
  225  CA5_B  IN  = M_G_CPU0_SB_CA<5>
  226  VSS98  POWER  = GND
  227  PAR_B  IN  = M_G_CPU0_SB_PAR
  228  VSS99  POWER  = GND
  229  CS1_B_N  IN  = M_G_CPU0_SB_CS_N<3>
  230  VSS100  POWER  = GND
  231  RFU5  TRI  = TP_CHG_CPU0_DIMM2_FRU_5
  232  RFU6  TRI  = TP_CHG_CPU0_DIMM2_FRU_6
  233  VSS101  POWER  = GND
  234  CB6_B  BI  = M_G_CPU0_SB_CB<6>
  235  VSS102  POWER  = GND
  236  CB7_B  BI  = M_G_CPU0_SB_CB<7>
  237  VSS103  POWER  = GND
  238  DQS4_B_C  BI  = M_G_CPU0_SB_DQS_DN<4>
  239  DQS4_B_T  BI  = M_G_CPU0_SB_DQS_DP<4>
  240  VSS104  POWER  = GND
  241  CB2_B  BI  = M_G_CPU0_SB_CB<2>
  242  VSS105  POWER  = GND
  243  CB3_B  BI  = M_G_CPU0_SB_CB<3>
  244  VSS106  POWER  = GND
  245  DQ2_B  BI  = M_G_CPU0_SB_DQ<2>
  246  VSS107  POWER  = GND
  247  DQ3_B  BI  = M_G_CPU0_SB_DQ<3>
  248  VSS108  POWER  = GND
  249  \dqs5_b_c||tdqs5_b_c\  BI  = M_G_CPU0_SB_DQS_DN<5>
  250  \dqs5_b_t||tdqs5_b_t\  BI  = M_G_CPU0_SB_DQS_DP<5>
  251  VSS109  POWER  = GND
  252  DQ6_B  BI  = M_G_CPU0_SB_DQ<6>
  253  VSS110  POWER  = GND
  254  DQ7_B  BI  = M_G_CPU0_SB_DQ<7>
  255  VSS111  POWER  = GND
  256  DQ10_B  BI  = M_G_CPU0_SB_DQ<10>
  257  VSS112  POWER  = GND
  258  DQ11_B  BI  = M_G_CPU0_SB_DQ<11>
  259  VSS113  POWER  = GND
  260  \dqs6_b_c||tdqs6_b_c\  BI  = M_G_CPU0_SB_DQS_DN<6>
  261  \dqs6_b_t||tdqs6_b_t\  BI  = M_G_CPU0_SB_DQS_DP<6>
  262  VSS114  POWER  = GND
  263  DQ14_B  BI  = M_G_CPU0_SB_DQ<14>
  264  VSS115  POWER  = GND
  265  DQ15_B  BI  = M_G_CPU0_SB_DQ<15>
  266  VSS116  POWER  = GND
  267  DQ18_B  BI  = M_G_CPU0_SB_DQ<18>
  268  VSS117  POWER  = GND
  269  DQ19_B  BI  = M_G_CPU0_SB_DQ<19>
  270  VSS118  POWER  = GND
  271  \dqs7_b_c||tdqs7_b_c\  BI  = M_G_CPU0_SB_DQS_DN<7>
  272  \dqs7_b_t||tdqs7_b_t\  BI  = M_G_CPU0_SB_DQS_DP<7>
  273  VSS119  POWER  = GND
  274  DQ22_B  BI  = M_G_CPU0_SB_DQ<22>
  275  VSS120  POWER  = GND
  276  DQ23_B  BI  = M_G_CPU0_SB_DQ<23>
  277  VSS121  POWER  = GND
  278  DQ26_B  BI  = M_G_CPU0_SB_DQ<26>
  279  VSS122  POWER  = GND
  280  DQ27_B  BI  = M_G_CPU0_SB_DQ<27>
  281  VSS123  POWER  = GND
  282  \dqs8_b_c||tdqs8_b_c\  BI  = M_G_CPU0_SB_DQS_DN<8>
  283  \dqs8_b_t||tdqs8_b_t\  BI  = M_G_CPU0_SB_DQS_DP<8>
  284  VSS124  POWER  = GND
  285  DQ30_B  BI  = M_G_CPU0_SB_DQ<30>
  286  VSS125  POWER  = GND
  287  DQ31_B  BI  = M_G_CPU0_SB_DQ<31>
  288  VSS126  POWER  = GND
  G1  G1  POWER  = GND
  G2  G2  POWER  = GND
  G3  G3  POWER  = GND
